# SCM (Grand Teton) — schematic parts with pin connectivity, parts 350–386 of 1428; source: Cadence DE-HDL packaged netlist (pstxprt.dat, pstxnet.dat, pstchip.dat)

GF1  FCONN168_ME1016810202011_SCM  EMPTY  pkg GOLD_168P_ME1016813401311  page 10
  A1  I2C_0_SCL  BI  = SMB_BMC_MM14_R1_SCL
  A2  I2C_0_SDA  BI  = SMB_BMC_MM14_R1_SDA
  A3  I2C_1_SCL  BI  = SMB_BMC_MM1_SCL
  A4  I2C_1_SDA  BI  = SMB_BMC_MM1_SDA
  A5  I2C_2_SCL  BI  = SMB_BMC_MM2_SCL_R1
  A6  I2C_2_SDA  BI  = SMB_BMC_MM2_SDA
  A7  I2C_3_SCL  BI  = SMB_BMC_MM3_SCL
  A8  I2C_3_SDA  BI  = SMB_BMC_MM3_SDA
  A9  I2C_4_SCL  BI  = SMB_BMC_MM4_SCL
  A10  I2C_4_SDA  BI  = SMB_BMC_MM4_SDA
  A11  I2C_5_SCL  BI  = SMB_BMC_MM5_SCL
  A12  I2C_5_SDA  BI  = SMB_BMC_MM5_SDA
  A13  GND_A13  POWER  = GND
  A14  CLK_100M_PCIE_DP  BI  = CLK_100M_PCH_DP
  A15  CLK_100M_PCIE_DN  BI  = CLK_100M_PCH_DN
  A16  GND_A16  POWER  = GND
  A17  PCIE_BMC_TX_DP  BI  = P2E_PCH_RX_DP
  A18  PCIE_BMC_TX_DN  BI  = P2E_PCH_RX_DN
  A19  GND_A19  POWER  = GND
  A20  PCIE_BMC_RX_DP  BI  = P2E_PCH_TX_C_DP
  A21  PCIE_BMC_RX_DN  BI  = P2E_PCH_TX_C_DN
  A22  GND_A22  POWER  = GND
  A23  I2C_6_SCL  BI  = SMB_BMC_MM6_SCL
  A24  I2C_6_SDA  BI  = SMB_BMC_MM6_SDA
  A25  I2C_7_SCL  BI  = SMB_BMC_MM7_SCL
  A26  I2C_7_SDA  BI  = SMB_BMC_MM7_SDA
  A27  I2C_8_SCL  BI  = SMB_BMC_MM8_SCL
  A28  I2C_8_SDA  BI  = SMB_BMC_MM8_SDA
  A29  I2C_9_SCL  BI  = SMB_BMC_MM9_SCL
  A30  I2C_9_SDA  BI  = SMB_BMC_MM9_SDA
  A31  I2C_10_SCL  BI  = SMB_BMC_MM10_SCL
  A32  I2C_10_SDA  BI  = SMB_BMC_MM10_SDA
  A33  GND_A33  POWER  = GND
  A34  JTAG_TCK  BI  = JTAG_MB_TCK
  A35  JTAG_TMS  BI  = JTAG_MB_TMS
  A36  JTAG_TDI  BI  = JTAG_MB_TDI
  A37  JTAG_TDO  BI  = JTAG_MB_TDO
  A38  I2C_11_SCL  BI  = SMB_BMC_MM12_SCL
  A39  I2C_11_SDA  BI  = SMB_BMC_MM12_SDA
  A40  I2C_12_SCL  BI  = SMB_BMC_MM13_SCL
  A41  I2C_12_SDA  BI  = SMB_BMC_MM13_SDA
  A42  GND_A42  POWER  = GND
  A43  HPM_FW_RECOVERY  BI  = FM_JTAG_SEL
  A44  HPM_STBY_RDY  BI  = PWRGD_PSU_AC_PWROK_R
  A45  HPM_STBY_EN  BI  = TP_GF_A45
  A46  HPM_STBY_RST_N  BI  = RST_MB_STBY_N
  A47  SYS_PWRBTN_N  BI  = SYS_PWRBTN_N
  A48  SYS_PWROK  BI  = PWRGD_SYS_PWROK
  A49  DBP_PREQ_N  BI  = FM_DBP_CPU_PREQ_GF_R_N
  A50  DBP_PRDY_N  BI  = FM_DBP_BMC_PRDY_N
  A51  RST_PLTRST_BUF_N  BI  = RST_PLTRST_N
  A52  SPARE1  BI  = FM_BMC_UARTSW_MSB_N
  A53  ROT_CPU_RST_N  BI  = RST_ROT_CPU_N
  A54  CHASI_N  BI  = FM_INTRUDER_N
  A55  SPARE0  BI  = FM_BMC_UARTSW_LSB_N
  A56  IRQ_N  BI  = IRQ_SMI_ACTIVE_GF_N
  A57  PRSNT1_N  BI  = FM_PRSNT_1_N
  A58  GND_A58  POWER  = GND
  A59  PCIE_HPM_RXP_0  BI  = USB3_FPNL_RXP
  A60  PCIE_HPM_RXN_0  BI  = USB3_FPNL_RXN
  A61  GND_A61  POWER  = GND
  A62  PCIE_HPM_RXP_1  BI  = TP_GF_A62
  A63  PCIE_HPM_RXN_1  BI  = TP_GF_A63
  A64  GND_A64  POWER  = GND
  A65  PCIE_HPM_RXP_2  BI  = P2E_GPU_RX_DP
  A66  PCIE_HPM_RXN_2  BI  = P2E_GPU_RX_DN
  A67  GND_A67  POWER  = GND
  A68  PCIE_HPM_RXP_3  BI  = CLK_100M_GPU_DP
  A69  PCIE_HPM_RXN_3  BI  = CLK_100M_GPU_DN
  A70  GND_A70  POWER  = GND
  B1  ESPI_CLK  BI  = ESPI_HOST_LPC_BMC_CLK
  B2  ESPI_CS0_N  BI  = ESPI_HOST_LPC_BMC_LFRAME_N
  B3  ESPI_ALERT_N  BI  = IRQ_BMC_LPC_SERIRQ_ESPI_GF
  B4  ESPI_RESET_N  BI  = RST_BMC_LPC_ESPI_N
  B5  ESPI_IO0  BI  = ESPI_LPC_LAD0_IO0
  B6  ESPI_IO1  BI  = ESPI_LPC_LAD1_IO1
  B7  ESPI_IO2  BI  = ESPI_LPC_LAD2_IO2
  B8  ESPI_IO3  BI  = ESPI_LPC_LAD3_IO3
  B9  RSVD3  BI  = LPC_ESPI_SEL
  B10  GND_B10  POWER  = GND
  B11  QSPI0_CLK  BI  = SPI_SYS_R_CLK
  B12  QSPI0_CS0_N  BI  = SPI_SYS_CS0_N
  B13  QSPI0_D0  BI  = SPI_SYS_R_MOSI
  B14  QSPI0_D1  BI  = SPI_SYS_R_MISO
  B15  QSPI0_D2  BI  = SPI_SYS_WP_R_IO2
  B16  QSPI0_D3  BI  = SPI_SYS_HOLD_R_IO3
  B17  GND_B17  POWER  = GND
  B18  NCSI_CLK  BI  = RMII_OCP_RCLKI
  B19  NCSI_CRS_DV  BI  = RMII_CSRDV
  B20  NCSI_TXEN  BI  = RMII_TXEN
  B21  NCSI_TXD0  BI  = RMII_TXD0
  B22  NCSI_TXD1  BI  = RMII_TXD1
  B23  NCSI_RXER  BI  = RMII_RXER
  B24  NCSI_RXD0  BI  = RMII_RXD0
  B25  NCSI_RXD1  BI  = RMII_RXD1
  B26  GND_B26  POWER  = GND
  B27  PECI_BMC  BI  = PECI_BMC
  B28  PVCCIO_PECI  POWER  = PVCCIO_PECI_BMC
  B29  SGPIO0_DO  BI  = SGPIO_DO_0
  B30  SGPIO_CLK  BI  = SGPIO_CLK_0
  B31  SGPIO0_DI  BI  = SGPIO_DI_0
  B32  SGPIO0_LD  BI  = SGPIO_LD_0
  B33  GND_B33  POWER  = GND
  B34  SGPIO1_DO  BI  = SGPIO_DO_1
  B35  RSVD2  TRI  = SGPIO_CLK_1
  B36  SGPIO1_DI  BI  = SGPIO_DI_1
  B37  SGPIO1_LD  BI  = SGPIO_LD_1
  B38  GND_B38  POWER  = GND
  B39  SGPIO_RESET_N  BI  = RST_SGPIO_RESET_N
  B40  SGPIO_INTR_N  BI  = IRQ_SGPIO_N
  B41  P3V0_BAT  POWER  = P3V_BAT_R
  B42  QSPI0_CS1_N  BI  = AC_PWR_BTN_N
  B43  QSPI1_CLK  BI  = QSPI_2_PLD_CLK
  B44  QSPI1_CS0_N  BI  = TP_GF1_B44
  B45  QSPI1_D0  BI  = QSPI_2_PLD_IO0
  B46  QSPI1_D1  BI  = QSPI_2_PLD_IO1
  B47  QSPI1_D2  BI  = QSPI_2_PLD_IO2
  B48  QSPI1_D3  BI  = QSPI_2_PLD_IO3
  B49  GND_B49  POWER  = GND
  B50  USB2_DP  BI  = USB_HOST_BMC_B_DP
  B51  USB2_DN  BI  = USB_HOST_BMC_B_DN
  B52  GND_B52  POWER  = GND
  B53  USB1_DP  BI  = USB_HOST_BMC_A_DP
  B54  USB1_DN  BI  = USB_HOST_BMC_A_DN
  B55  GND_B55  POWER  = GND
  B56  RSVD0  TRI  = USB_FPNL_DP
  B57  RSVD1  TRI  = USB_FPNL_DN
  B58  GND_B58  POWER  = GND
  B59  PCIE_HPM_TXP_0  BI  = USB3_FPNL_TXP
  B60  PCIE_HPM_TXN_0  BI  = USB3_FPNL_TXN
  B61  GND_B61  POWER  = GND
  B62  PCIE_HPM_TXP_1  BI  = TP_GF_B62
  B63  PCIE_HPM_TXN_1  BI  = TP_GF_B63
  B64  GND_B64  POWER  = GND
  B65  PCIE_HPM_TXP_2  BI  = P2E_GPU_TX_C_DP
  B66  PCIE_HPM_TXN_2  BI  = P2E_GPU_TX_C_DN
  B67  GND_B67  POWER  = GND
  B68  PCIE_HPM_TXP_3  BI  = HDD_LED_R_N
  B69  PCIE_HPM_TXN_3  BI  = PCH_BEEP_R_LED
  B70  GND_B70  POWER  = GND
  OA1  P12V_AUX_OA1  POWER  = P12V_AUX
  OA2  P12V_AUX_OA2  POWER  = P12V_AUX
  OA3  GND_OA3  POWER  = GND
  OA4  GND_OA4  POWER  = GND
  OA5  I3C_0_SCL  BI  = I3C1_SPD_SCL
  OA6  I3C_0_SDA  BI  = I3C1_SPD_SDA
  OA7  I3C_1_SCL  BI  = I3C2_SPD_SCL
  OA8  I3C_1_SDA  BI  = I3C2_SPD_SDA
  OA9  I3C_2_SCL  BI  = I3C3_SPD_SCL
  OA10  I3C_2_SDA  BI  = I3C3_SPD_SDA
  OA11  I3C_3_SCL  BI  = I3C4_SPD_SCL
  OA12  I3C_3_SDA  BI  = I3C4_SPD_SDA
  OA13  GND_OA13  POWER  = GND
  OA14  VIRTUAL_RESEAT  BI  = FM_VIRTUAL_RESEAT
  OB1  P12V_AUX_OB1  POWER  = P12V_AUX
  OB2  P12V_AUX_OB2  POWER  = P12V_AUX
  OB3  PRSNT0_N  BI  = FM_PRSNT_0_R_N
  OB4  GND_OB4  POWER  = GND
  OB5  UART1_SCM_TX  BI  = UART_BIC_GF_TXD
  OB6  UART1_SCM_RX  BI  = UART_BIC_GF_RXD
  OB7  GND_OB7  POWER  = GND
  OB8  UART0_SCM_TX  BI  = UART_SYS_DBG_TX
  OB9  UART0_SCM_RX  BI  = UART_SYS_DBG_RX
  OB10  GND_OB10  POWER  = GND
  OB11  SPI0_CLK  BI  = RST_SRST_PLD_BMC_R_N
  OB12  SPI0_CS_N  BI  = SPI_TPM_CS_N
  OB13  SPI0_MOSI  BI  = H_CPU_CATERR_LVC2_R2_N
  OB14  SPI0_MISO  BI  = FM_SOL_UART_CH_SEL

H1  HOLE  EMPTY  pkg TH  page 57 : 1 = GND
H2  HOLE  EMPTY  pkg TH  page 57 : 1 = NC
H2B1  HOLE  EMPTY  pkg TH  page 57 : 1 = NC
H2B2  HOLE  EMPTY  pkg TH  page 57 : 1 = NC
H3  HOLE  EMPTY  pkg TH  page 57 : 1 = GND
H4  HOLE  EMPTY  pkg TH  page 57 : 1 = GND
H5  HOLE  EMPTY  pkg TH  page 57 : 1 = GND
H6  HOLE  EMPTY  pkg TH  page 57 : 1 = GND
H7  HOLE  EMPTY  pkg TH  page 57 : 1 = GND
H9  HOLE  EMPTY  pkg TH  page 57 : 1 = GND

J1  SCONN3_212H9103GBR1  SCONN3_212-H91-03GBR1 IO  pkg HEADER1X3SXE_H367  page 25
  1  \1\  BI  = PU_J1_P1
  2  \2\  BI  = FLASH_LATCH_Q_N_R2
  3  \3\  BI  = NC_J1_P3

J2  CONN9_GSB3111315HR  IO  pkg USB1XBH  page 29
  1  VBUS  POWER  = P5V_USB_REAR
  2  \d-\  BI  = USB2_01_F_DN
  3  \d+\  BI  = USB2_01_F_DP
  4  GND  POWER  = GND
  5  \ssrx-\  OUT  = USB3_01_FB_RXN
  6  \ssrx+\  OUT  = USB3_01_FB_RXP
  7  GND_D  POWER  = DEBUG_PORT_PRSNT_R
  8  \sstx-\  IN  = USB3_01_FB_TXN
  9  \sstx+\  IN  = USB3_01_FB_TXP
  G1  G1  POWER  = GND
  G2  G2  POWER  = GND

J4  SCONN67_NASA0S6730TS67  SCONN67_NASA0-S6730-TS67 IO  pkg CON_F67S2H2D2S_P0-5W7-55_LUVXM  page 21
  1  \1\  BI  = GND
  2  \2\  BI  = P3V3_AUX
  3  \3\  BI  = SPI_BMC_BT_WP1_N_R
  4  \4\  BI  = P3V3_AUX
  5  \5\  BI  = SPI_BMC_BT_WP0_N_R
  6  \6\  BI  = NC
  7  \7\  BI  = GND
  16  \16\  BI  = BSM_PRSNT_N
  17  \17\  BI  = NC
  18  \18\  BI  = GND
  19  \19\  BI  = RST_SPI_BMC_FLASH_R2_N
  20  \20\  BI  = NC
  21  \21\  BI  = RST_SPI_BMC_FLASH_R1_N
  22  \22\  BI  = NC
  23  \23\  BI  = GND
  24  \24\  BI  = GND
  25  \25\  BI  = SPI_BMC_IO1_FLASH_R
  26  \26\  BI  = SPI_BMC_HOLD1_N
  27  \27\  BI  = SPI_BMC_IO0_FLASH_R
  28  \28\  BI  = SPI_BMC_HOLD0_N
  29  \29\  BI  = GND
  30  \30\  BI  = GND
  31  \31\  BI  = SPI_BMC_CLK_FLASH_R
  32  \32\  BI  = NC
  33  \33\  BI  = GND
  34  \34\  BI  = NC
  35  \35\  BI  = SPI_BMC_CS1_FLASH_R_N
  36  \36\  BI  = GND
  37  \37\  BI  = SPI_BMC_CS0_FLASH_R_N
  38  \38\  BI  = NC
  39  \39\  BI  = GND
  40  \40\  BI  = SMB_BMC_MM16_R1_SCL
  41  \41\  BI  = NC
  42  \42\  BI  = SMB_BMC_MM16_R1_SDA
  43  \43\  BI  = NC
  44  \44\  BI  = NC
  45  \45\  BI  = GND
  46  \46\  BI  = EMMC_WP
  47  \47\  BI  = NC
  48  \48\  BI  = NC
  49  \49\  BI  = NC
  50  \50\  BI  = NC
  51  \51\  BI  = GND
  52  \52\  BI  = EMMC_DT7_R
  53  \53\  BI  = NC
  54  \54\  BI  = EMMC_DT6_R
  55  \55\  BI  = EMMC_CLK_R
  56  \56\  BI  = EMMC_DT5_R
  57  \57\  BI  = GND
  58  \58\  BI  = EMMC_DT4_R
  59  \59\  BI  = EMMC_CMD_R
  60  \60\  BI  = NC
  61  \61\  BI  = EMMC_DT3_R
  62  \62\  BI  = NC
  63  \63\  BI  = GND
  64  \64\  BI  = NC
  65  \65\  BI  = EMMC_DT2_R
  66  \66\  BI  = BMC_EMMC_RST_N
  67  \67\  BI  = EMMC_DT1_R
  68  \68\  BI  = NC
  69  \69\  BI  = GND
  70  \70\  BI  = NC
  71  \71\  BI  = EMMC_DT0_R
  72  \72\  BI  = P3V3_AUX
  73  \73\  BI  = NC
  74  \74\  BI  = P3V3_AUX
  75  \75\  BI  = GND
  G1  G1  POWER  = GND
  G2  G2  POWER  = GND

J5  SCONN11_9192031111LF  SCONN11_91920-31111LF IO  pkg CON_F11S2H2S_P1W4-22_LDH  page 46
  1  \1\  BI  = SPI_SYS_R1_CLK
  2  \2\  BI  = RST_PLTRST_TPM_N
  3  \3\  BI  = SPI_SYS_R1_MOSI
  4  \4\  BI  = SPI_SYS_R1_MISO
  5  \5\  BI  = SPI_TPM_CS_N_R
  6  \6\  BI  = SMB_PCH_TPM_SDA
  7  \7\  BI  = P3V3_AUX
  8  \8\  BI  = FM_TPM_PRSNT_0_N
  9  \9\  BI  = IRQ_PCH_TPM_SPI_R_N
  10  \10\  BI  = SMB_PCH_TPM_SCL
  11  \11\  BI  = GND
  G1  G1  POWER  = GND
  G2  G2  POWER  = GND

J6  SCONN3_21291035BR2  SCONN3_212-91-035BR2 EMPTY  pkg HEADER1X3SXF  page 30
  1  \1\  BI  = UART_BMC_5_TXD_BUF_R
  2  \2\  BI  = GND
  3  \3\  BI  = UART_BMC_5_RXD_BUF

J7  CONN8_210HP1080BR1  CONN8_210-HP1-080BR1 IO  pkg HEADER1X8XE  page 32
  1  \1\  BI  = J7_P1
  2  \2\  BI  = JTAG_SCM_CONN_TDO
  3  \3\  BI  = JTAG_SCM_CONN_TDI
  4  \4\  BI  = JTAG_SCM_PLD_R1_JTAGEN
  5  \5\  BI  = TP_PLD_CONN_P5
  6  \6\  BI  = JTAG_SCM_CONN_TMS
  7  \7\  BI  = GND
  8  \8\  BI  = JTAG_SCM_CONN_TCK

J8  SCONN13_502280130CV01  SCONN13_50228-0130C-V01 IO  pkg CON_13S1H2S_P1XA  page 23
  1  \1\  BI  = V_DACR_IO
  2  \2\  BI  = GND
  3  \3\  BI  = V_DACG_IO
  4  \4\  BI  = GND
  5  \5\  BI  = V_DACB_IO
  6  \6\  BI  = GND
  7  \7\  BI  = V_VGAVS_BUF
  8  \8\  BI  = GND
  9  \9\  BI  = V_VGAHS_BUF
  10  \10\  BI  = GND
  11  \11\  BI  = V_BMC_LS_DDC_SDA_R
  12  \12\  BI  = V_BMC_LS_DDC_SCL_R
  13  \13\  BI  = CRT_VCC5_2_FUSE
  G1  G1  POWER  = GND
  G2  G2  POWER  = GND

J9  PICOPROBE_BXA  DELTA-L 4.0 EMPTY  pkg TRIANG_LAUNCH_3PXB  page 58
  1  \1_p\  POWER  = 85_5INCH_TOP_DN
  2  \2_n\  POWER  = 85_5INCH_TOP_DP
  3  \3_g\  POWER  = GND_P1

J10  SCONN11_9192031111LF  SCONN11_91920-31111LF IO  pkg CON_F11S2H2S_P1W4-22_LDH  page 46
  1  \1\  BI  = SPI_BMC_TPM_CLK_R
  2  \2\  BI  = RST_BMC_EXTRST_R3_N
  3  \3\  BI  = SPI_BMC_TPM_MOSI_R
  4  \4\  BI  = SPI_BMC_TPM_MISO_R
  5  \5\  BI  = SPI_BMC_TPM_CS2_N_R
  6  \6\  BI  = SMB_BMC_TPM_MM16_SDA
  7  \7\  BI  = P3V3_AUX
  8  \8\  BI  = FM_TPM_PRSNT_1_N
  9  \9\  BI  = IRQ_BMC_TPM_SPI_R_N
  10  \10\  BI  = SMB_BMC_TPM_MM16_SCL
  11  \11\  BI  = GND
  G1  G1  POWER  = GND
  G2  G2  POWER  = GND

J11  PICOPROBE_BXA  DELTA-L 4.0 EMPTY  pkg TRIANG_LAUNCH_3PXB  page 58
  1  \1_p\  POWER  = 85_5INCH_IN1_DN
  2  \2_n\  POWER  = 85_5INCH_IN1_DP
  3  \3_g\  POWER  = GND_P1

J12  PICOPROBE_BXA  DELTA-L 4.0 EMPTY  pkg TRIANG_LAUNCH_3PXB  page 58
  1  \1_p\  POWER  = 85_5INCH_TOP_DP
  2  \2_n\  POWER  = 85_5INCH_TOP_DN
  3  \3_g\  POWER  = GND_P1

J13  SCONN3_212H9103GBR1  SCONN3_212-H91-03GBR1 EMPTY  pkg HEADER1X3SXE_H367  page 31
  1  \1\  BI  = PU_J13_P1
  2  \2\  BI  = FM_DBG_SW_N
  3  \3\  BI  = GND

J14  CONN8_TSW10407FD  CONN8_TSW-104-07-F-D EMPTY  pkg HEADER2X4XF  page 26
  1  \1\  BI  = P3V3_AUX
  2  \2\  BI  = SMB_TMP421_BMC_MM2_SDA
  3  \3\  BI  = TMC75_A0
  4  \4\  BI  = SMB_TMP421_BMC_MM2_SCL
  5  \5\  BI  = TMC75_A1
  6  \6\  BI  = SMB_BMC_ALERT16_R_N
  7  \7\  BI  = TMC75_A2
  8  \8\  BI  = GND

J16  PICOPROBE_BXA  DELTA-L 4.0 EMPTY  pkg TRIANG_LAUNCH_3PXB  page 58
  1  \1_p\  POWER  = 85_5INCH_IN4_DN
  2  \2_n\  POWER  = 85_5INCH_IN4_DP
  3  \3_g\  POWER  = GND_P1

J17  PICOPROBE_BXA  DELTA-L 4.0 EMPTY  pkg TRIANG_LAUNCH_3PXB  page 58
  1  \1_p\  POWER  = 85_5INCH_BOT_DN
  2  \2_n\  POWER  = 85_5INCH_BOT_DP
  3  \3_g\  POWER  = GND_P1

J19  PICOPROBE_BXA  DELTA-L 4.0 EMPTY  pkg TRIANG_LAUNCH_3PXB  page 58
  1  \1_p\  POWER  = 85_5INCH_IN4_DP
  2  \2_n\  POWER  = 85_5INCH_IN4_DN
  3  \3_g\  POWER  = GND_P1

J20  PICOPROBE_BXA  DELTA-L 4.0 EMPTY  pkg TRIANG_LAUNCH_3PXB  page 58
  1  \1_p\  POWER  = 85_5INCH_BOT_DP
  2  \2_n\  POWER  = 85_5INCH_BOT_DN
  3  \3_g\  POWER  = GND_P1

J22  PICOPROBE_BXA  DELTA-L 4.0 EMPTY  pkg TRIANG_LAUNCH_3PXB  page 58
  1  \1_p\  POWER  = 85_10INCH_TOP_DP
  2  \2_n\  POWER  = 85_10INCH_TOP_DN
  3  \3_g\  POWER  = GND_P1

J23  PICOPROBE_BXA  DELTA-L 4.0 EMPTY  pkg TRIANG_LAUNCH_3PXB  page 58
  1  \1_p\  POWER  = 85_10INCH_IN4_DP
  2  \2_n\  POWER  = 85_10INCH_IN4_DN
  3  \3_g\  POWER  = GND_P1

J24  PICOPROBE_BXA  DELTA-L 4.0 EMPTY  pkg TRIANG_LAUNCH_3PXB  page 58
  1  \1_p\  POWER  = 85_10INCH_BOT_DP
  2  \2_n\  POWER  = 85_10INCH_BOT_DN
  3  \3_g\  POWER  = GND_P1

J25  PICOPROBE_BXA  DELTA-L 4.0 EMPTY  pkg TRIANG_LAUNCH_3PXB  page 58
  1  \1_p\  POWER  = 85_10INCH_TOP_DN
  2  \2_n\  POWER  = 85_10INCH_TOP_DP
  3  \3_g\  POWER  = GND_P1

J26  PICOPROBE_BXA  DELTA-L 4.0 EMPTY  pkg TRIANG_LAUNCH_3PXB  page 58
  1  \1_p\  POWER  = 85_10INCH_IN4_DN
  2  \2_n\  POWER  = 85_10INCH_IN4_DP
  3  \3_g\  POWER  = GND_P1

J27  PICOPROBE_BXA  DELTA-L 4.0 EMPTY  pkg TRIANG_LAUNCH_3PXB  page 58
  1  \1_p\  POWER  = 85_10INCH_BOT_DN
  2  \2_n\  POWER  = 85_10INCH_BOT_DP
  3  \3_g\  POWER  = GND_P1

J28  PICOPROBE_BXA  DELTA-L 4.0 EMPTY  pkg TRIANG_LAUNCH_3PXB  page 58
  1  \1_p\  POWER  = 85_10INCH_IN1_DN
  2  \2_n\  POWER  = 85_10INCH_IN1_DP
  3  \3_g\  POWER  = GND_P1

J29  PICOPROBE_BXA  DELTA-L 4.0 EMPTY  pkg TRIANG_LAUNCH_3PXB  page 58
  1  \1_p\  POWER  = 85_5INCH_IN1_DP
  2  \2_n\  POWER  = 85_5INCH_IN1_DN
  3  \3_g\  POWER  = GND_P1

J30  PICOPROBE_BXA  DELTA-L 4.0 EMPTY  pkg TRIANG_LAUNCH_3PXB  page 58
  1  \1_p\  POWER  = 85_10INCH_IN1_DP
  2  \2_n\  POWER  = 85_10INCH_IN1_DN
  3  \3_g\  POWER  = GND_P1
